FILE_TYPE = MACRO_DRAWING;
SET COLOR_WIRE YELLOW;
SET COLOR_PROP ORANGE;
SET COLOR_DOT WHITE;
SET COLOR_ARC YELLOW;
SET COLOR_BODY GREEN;
SET COLOR_NOTE PURPLE;
SET PROP_DISPLAY VALUE;
SET PAGE_NUMBER P47;
SET PATH_NUMBER P63;
FORCEADD Q_LED..1
(3875 2600);
FORCEPROP 2 LAST PACK_TYPE SMLF
J 0
(3650 2675);
DISPLAY 0.510638 (3650 2675);
PAINT SKYBLUE (3650 2675);
FORCEPROP 1 LAST PART_NUMBER BERD0034Z07
J 0
(3850 2675);
DISPLAY 0.510638 (3850 2675);
PAINT WHITE (3850 2675);
FORCEPROP 1 LAST MATERIAL IC
J 0
(3775 2680);
DISPLAY 0.510638 (3775 2680);
PAINT SKYBLUE (3775 2680);
FORCEPROP 2 LAST COLOR LED_RED
J 0
(3950 2725);
DISPLAY 0.808511 (3950 2725);
PAINT GREEN (3950 2725);
FORCEPROP 2 LAST CDS_LIB pure_quanta
J 0
(3875 2600);
DISPLAY INVISIBLE (3875 2600);
FORCEPROP 0 LAST MANUF_PN 19-217/R6C-P1Q2/3T
J 0
(3775 2875);
DISPLAY 0.808511 (3775 2875);
DISPLAY INVISIBLE (3775 2875);
FORCEPROP 1 LAST NEEDS_NO_SIZE TRUE
J 0
(3875 2600);
DISPLAY 0.468085 (3875 2600);
PAINT GREEN (3875 2600);
DISPLAY INVISIBLE (3875 2600);
FORCEPROP 1 LAST PATH I10
J 0
(4000 2680);
DISPLAY 0.723404 (4000 2680);
PAINT GREEN (4000 2680);
DISPLAY INVISIBLE (4000 2680);
FORCEPROP 1 LAST LOCATION D4
J 0
(3775 2785);
DISPLAY 0.702128 (3775 2785);
PAINT AQUA (3775 2785);
FORCEPROP 0 LASTPIN (3725 2600) $PN A
J 2
(3715 2610);
DISPLAY 0.680851 (3715 2610);
PAINT MONO (3715 2610);
FORCEPROP 0 LASTPIN (4025 2600) $PN C
J 0
(4035 2610);
DISPLAY 0.680851 (4035 2610);
PAINT MONO (4035 2610);
FORCEPROP 0 LAST $SEC 1
J 0
(3775 2825);
DISPLAY 0.680851 (3775 2825);
PAINT MONO (3775 2825);
DISPLAY INVISIBLE (3775 2825);
FORCEPROP 0 LAST CDS_SEC 1
J 0
(3775 2825);
DISPLAY 1.021277 (3775 2825);
DISPLAY INVISIBLE (3775 2825);
FORCEADD Q_LED..1
(3875 2000);
FORCEPROP 2 LAST PACK_TYPE SMLF
J 0
(3675 2075);
DISPLAY 0.510638 (3675 2075);
PAINT SKYBLUE (3675 2075);
FORCEPROP 1 LAST PART_NUMBER BEGR0278Z00
J 0
(3850 2075);
DISPLAY 0.510638 (3850 2075);
PAINT WHITE (3850 2075);
FORCEPROP 1 LAST MATERIAL IC
J 0
(3775 2080);
DISPLAY 0.510638 (3775 2080);
PAINT SKYBLUE (3775 2080);
FORCEPROP 2 LAST COLOR LED_GREEN
J 0
(3975 2125);
DISPLAY 0.808511 (3975 2125);
PAINT GREEN (3975 2125);
FORCEPROP 2 LAST CDS_LIB pure_quanta
J 0
(3875 2000);
DISPLAY INVISIBLE (3875 2000);
FORCEPROP 1 LAST NEEDS_NO_SIZE TRUE
J 0
(3875 2000);
DISPLAY 0.468085 (3875 2000);
PAINT GREEN (3875 2000);
DISPLAY INVISIBLE (3875 2000);
FORCEPROP 0 LAST MANUF_PN 19-213/GVC-AMNB/3T
J 0
(3775 2275);
DISPLAY 0.808511 (3775 2275);
DISPLAY INVISIBLE (3775 2275);
FORCEPROP 1 LAST PATH I11
J 0
(4000 2080);
DISPLAY 0.723404 (4000 2080);
PAINT GREEN (4000 2080);
DISPLAY INVISIBLE (4000 2080);
FORCEPROP 1 LAST LOCATION D2
J 0
(3775 2185);
DISPLAY 0.702128 (3775 2185);
PAINT AQUA (3775 2185);
FORCEPROP 0 LASTPIN (3725 2000) $PN A
J 2
(3715 2010);
DISPLAY 0.680851 (3715 2010);
PAINT MONO (3715 2010);
FORCEPROP 0 LASTPIN (4025 2000) $PN C
J 0
(4035 2010);
DISPLAY 0.680851 (4035 2010);
PAINT MONO (4035 2010);
FORCEPROP 0 LAST $SEC 1
J 0
(3775 2225);
DISPLAY 0.680851 (3775 2225);
PAINT MONO (3775 2225);
DISPLAY INVISIBLE (3775 2225);
FORCEPROP 0 LAST CDS_SEC 1
J 0
(3775 2225);
DISPLAY 1.021277 (3775 2225);
DISPLAY INVISIBLE (3775 2225);
FORCEADD Q_LED..1
(3875 2900);
FORCEPROP 2 LAST PACK_TYPE SMLF
J 0
(3650 2975);
DISPLAY 0.510638 (3650 2975);
PAINT SKYBLUE (3650 2975);
FORCEPROP 1 LAST PART_NUMBER BERD0034Z07
J 0
(3850 2975);
DISPLAY 0.510638 (3850 2975);
PAINT WHITE (3850 2975);
FORCEPROP 1 LAST MATERIAL IC
J 0
(3775 2980);
DISPLAY 0.510638 (3775 2980);
PAINT SKYBLUE (3775 2980);
FORCEPROP 2 LAST COLOR LED_RED
J 0
(3950 3025);
DISPLAY 0.808511 (3950 3025);
PAINT GREEN (3950 3025);
FORCEPROP 2 LAST CDS_LIB pure_quanta
J 0
(3875 2900);
DISPLAY INVISIBLE (3875 2900);
FORCEPROP 0 LAST MANUF_PN 19-217/R6C-P1Q2/3T
J 0
(3775 3175);
DISPLAY 0.808511 (3775 3175);
DISPLAY INVISIBLE (3775 3175);
FORCEPROP 1 LAST NEEDS_NO_SIZE TRUE
J 0
(3875 2900);
DISPLAY 0.468085 (3875 2900);
PAINT GREEN (3875 2900);
DISPLAY INVISIBLE (3875 2900);
FORCEPROP 1 LAST PATH I12
J 0
(4000 2980);
DISPLAY 0.723404 (4000 2980);
PAINT GREEN (4000 2980);
DISPLAY INVISIBLE (4000 2980);
FORCEPROP 1 LAST LOCATION D5
J 0
(3775 3085);
DISPLAY 0.702128 (3775 3085);
PAINT AQUA (3775 3085);
FORCEPROP 0 LASTPIN (3725 2900) $PN A
J 2
(3715 2910);
DISPLAY 0.680851 (3715 2910);
PAINT MONO (3715 2910);
FORCEPROP 0 LASTPIN (4025 2900) $PN C
J 0
(4035 2910);
DISPLAY 0.680851 (4035 2910);
PAINT MONO (4035 2910);
FORCEPROP 0 LAST $SEC 1
J 0
(3775 3125);
DISPLAY 0.680851 (3775 3125);
PAINT MONO (3775 3125);
DISPLAY INVISIBLE (3775 3125);
FORCEPROP 0 LAST CDS_SEC 1
J 0
(3775 3125);
DISPLAY 1.021277 (3775 3125);
DISPLAY INVISIBLE (3775 3125);
FORCEADD Q_LED..1
(3875 2300);
FORCEPROP 2 LAST COLOR LED_GREEN
J 0
(3975 2425);
DISPLAY 0.808511 (3975 2425);
PAINT GREEN (3975 2425);
FORCEPROP 2 LAST PACK_TYPE SMLF
J 0
(3675 2375);
DISPLAY 0.510638 (3675 2375);
PAINT SKYBLUE (3675 2375);
FORCEPROP 1 LAST PART_NUMBER BEGR0278Z00
J 0
(3850 2375);
DISPLAY 0.510638 (3850 2375);
PAINT WHITE (3850 2375);
FORCEPROP 1 LAST MATERIAL IC
J 0
(3775 2380);
DISPLAY 0.510638 (3775 2380);
PAINT SKYBLUE (3775 2380);
FORCEPROP 2 LAST CDS_LIB pure_quanta
J 0
(3875 2300);
DISPLAY INVISIBLE (3875 2300);
FORCEPROP 1 LAST NEEDS_NO_SIZE TRUE
J 0
(3875 2300);
DISPLAY 0.468085 (3875 2300);
PAINT GREEN (3875 2300);
DISPLAY INVISIBLE (3875 2300);
FORCEPROP 0 LAST MANUF_PN 19-213/GVC-AMNB/3T
J 0
(3775 2575);
DISPLAY 0.808511 (3775 2575);
DISPLAY INVISIBLE (3775 2575);
FORCEPROP 1 LAST PATH I13
J 0
(4000 2380);
DISPLAY 0.723404 (4000 2380);
PAINT GREEN (4000 2380);
DISPLAY INVISIBLE (4000 2380);
FORCEPROP 1 LAST LOCATION D3
J 0
(3775 2485);
DISPLAY 0.702128 (3775 2485);
PAINT AQUA (3775 2485);
FORCEPROP 0 LASTPIN (3725 2300) $PN A
J 2
(3715 2310);
DISPLAY 0.680851 (3715 2310);
PAINT MONO (3715 2310);
FORCEPROP 0 LASTPIN (4025 2300) $PN C
J 0
(4035 2310);
DISPLAY 0.680851 (4035 2310);
PAINT MONO (4035 2310);
FORCEPROP 0 LAST $SEC 1
J 0
(3775 2525);
DISPLAY 0.680851 (3775 2525);
PAINT MONO (3775 2525);
DISPLAY INVISIBLE (3775 2525);
FORCEPROP 0 LAST CDS_SEC 1
J 0
(3775 2525);
DISPLAY 1.021277 (3775 2525);
DISPLAY INVISIBLE (3775 2525);
FORCEADD Q_LED..1
(3875 3200);
FORCEPROP 1 LAST PART_NUMBER BERD0034Z07
J 0
(3850 3275);
DISPLAY 0.510638 (3850 3275);
PAINT WHITE (3850 3275);
FORCEPROP 2 LAST PACK_TYPE SMLF
J 0
(3650 3275);
DISPLAY 0.510638 (3650 3275);
PAINT SKYBLUE (3650 3275);
FORCEPROP 1 LAST MATERIAL IC
J 0
(3775 3280);
DISPLAY 0.510638 (3775 3280);
PAINT SKYBLUE (3775 3280);
FORCEPROP 2 LAST COLOR LED_RED
J 0
(3950 3325);
DISPLAY 0.808511 (3950 3325);
PAINT GREEN (3950 3325);
FORCEPROP 2 LAST CDS_LIB pure_quanta
J 0
(3875 3200);
DISPLAY INVISIBLE (3875 3200);
FORCEPROP 0 LAST MANUF_PN 19-217/R6C-P1Q2/3T
J 0
(3775 3475);
DISPLAY 0.808511 (3775 3475);
DISPLAY INVISIBLE (3775 3475);
FORCEPROP 1 LAST NEEDS_NO_SIZE TRUE
J 0
(3875 3200);
DISPLAY 0.468085 (3875 3200);
PAINT GREEN (3875 3200);
DISPLAY INVISIBLE (3875 3200);
FORCEPROP 1 LAST PATH I14
J 0
(4000 3280);
DISPLAY 0.723404 (4000 3280);
PAINT GREEN (4000 3280);
DISPLAY INVISIBLE (4000 3280);
FORCEPROP 1 LAST LOCATION D6
J 0
(3775 3385);
DISPLAY 0.702128 (3775 3385);
PAINT AQUA (3775 3385);
FORCEPROP 0 LASTPIN (3725 3200) $PN A
J 2
(3715 3210);
DISPLAY 0.680851 (3715 3210);
PAINT MONO (3715 3210);
FORCEPROP 0 LASTPIN (4025 3200) $PN C
J 0
(4035 3210);
DISPLAY 0.680851 (4035 3210);
PAINT MONO (4035 3210);
FORCEPROP 0 LAST $SEC 1
J 0
(3775 3425);
DISPLAY 0.680851 (3775 3425);
PAINT MONO (3775 3425);
DISPLAY INVISIBLE (3775 3425);
FORCEPROP 0 LAST CDS_SEC 1
J 0
(3775 3425);
DISPLAY 1.021277 (3775 3425);
DISPLAY INVISIBLE (3775 3425);
FORCEADD Q_RES..1
(2675 3500);
FORCEPROP 1 LAST VALUE 750
J 2
(2650 3400);
DISPLAY 0.510638 (2650 3400);
PAINT SKYBLUE (2650 3400);
FORCEPROP 1 LAST TOLERANCE 1%
J 0
(2675 3400);
DISPLAY 0.510638 (2675 3400);
PAINT SKYBLUE (2675 3400);
FORCEPROP 1 LAST WATTAGE 1/16W
J 2
(2425 3400);
DISPLAY 0.510638 (2425 3400);
PAINT SKYBLUE (2425 3400);
FORCEPROP 1 LAST MATERIAL CHIP
J 0
(2450 3400);
DISPLAY 0.510638 (2450 3400);
PAINT SKYBLUE (2450 3400);
FORCEPROP 1 LAST PACK_TYPE 0402LF
J 0
(2750 3400);
DISPLAY 0.510638 (2750 3400);
PAINT SKYBLUE (2750 3400);
FORCEPROP 1 LAST PART_NUMBER CS17502FB03
J 0
(2300 3525);
DISPLAY 0.510638 (2300 3525);
PAINT WHITE (2300 3525);
FORCEPROP 2 LAST CDS_LIB pure_quanta
J 0
(2675 3500);
DISPLAY INVISIBLE (2675 3500);
FORCEPROP 1 LAST PATH I18
J 0
(2625 3650);
DISPLAY 0.978723 (2625 3650);
PAINT WHITE (2625 3650);
DISPLAY INVISIBLE (2625 3650);
FORCEPROP 1 LAST LOCATION R597
J 0
(2625 3550);
DISPLAY 0.702128 (2625 3550);
PAINT YELLOW (2625 3550);
FORCEPROP 0 LAST $SEC 1
J 0
(2625 3600);
DISPLAY 0.680851 (2625 3600);
PAINT MONO (2625 3600);
DISPLAY INVISIBLE (2625 3600);
FORCEPROP 0 LAST CDS_SEC 1
J 0
(2625 3600);
DISPLAY 1.021277 (2625 3600);
DISPLAY INVISIBLE (2625 3600);
FORCEPROP 1 LASTPIN (2575 3500) $PN 1
J 0
(2587 3512);
DISPLAY 0.808511 (2587 3512);
PAINT WHITE (2587 3512);
DISPLAY INVISIBLE (2587 3512);
FORCEPROP 1 LASTPIN (2775 3500) $PN 2
J 0
(2737 3512);
DISPLAY 0.808511 (2737 3512);
PAINT WHITE (2737 3512);
DISPLAY INVISIBLE (2737 3512);
FORCEADD Q_RES..1
(2675 3200);
FORCEPROP 1 LAST VALUE 750
J 2
(2650 3100);
DISPLAY 0.510638 (2650 3100);
PAINT SKYBLUE (2650 3100);
FORCEPROP 1 LAST TOLERANCE 1%
J 0
(2675 3100);
DISPLAY 0.510638 (2675 3100);
PAINT SKYBLUE (2675 3100);
FORCEPROP 1 LAST WATTAGE 1/16W
J 2
(2425 3100);
DISPLAY 0.510638 (2425 3100);
PAINT SKYBLUE (2425 3100);
FORCEPROP 1 LAST MATERIAL CHIP
J 0
(2450 3100);
DISPLAY 0.510638 (2450 3100);
PAINT SKYBLUE (2450 3100);
FORCEPROP 1 LAST PACK_TYPE 0402LF
J 0
(2750 3100);
DISPLAY 0.510638 (2750 3100);
PAINT SKYBLUE (2750 3100);
FORCEPROP 1 LAST PART_NUMBER CS17502FB03
J 0
(2300 3225);
DISPLAY 0.510638 (2300 3225);
PAINT WHITE (2300 3225);
FORCEPROP 2 LAST CDS_LIB pure_quanta
J 0
(2675 3200);
DISPLAY INVISIBLE (2675 3200);
FORCEPROP 1 LAST PATH I20
J 0
(2625 3350);
DISPLAY 0.978723 (2625 3350);
PAINT WHITE (2625 3350);
DISPLAY INVISIBLE (2625 3350);
FORCEPROP 1 LAST LOCATION R598
J 0
(2625 3250);
DISPLAY 0.702128 (2625 3250);
PAINT YELLOW (2625 3250);
FORCEPROP 0 LAST $SEC 1
J 0
(2625 3300);
DISPLAY 0.680851 (2625 3300);
PAINT MONO (2625 3300);
DISPLAY INVISIBLE (2625 3300);
FORCEPROP 0 LAST CDS_SEC 1
J 0
(2625 3300);
DISPLAY 1.021277 (2625 3300);
DISPLAY INVISIBLE (2625 3300);
FORCEPROP 1 LASTPIN (2575 3200) $PN 1
J 0
(2587 3212);
DISPLAY 0.808511 (2587 3212);
PAINT WHITE (2587 3212);
DISPLAY INVISIBLE (2587 3212);
FORCEPROP 1 LASTPIN (2775 3200) $PN 2
J 0
(2737 3212);
DISPLAY 0.808511 (2737 3212);
PAINT WHITE (2737 3212);
DISPLAY INVISIBLE (2737 3212);
FORCEADD Q_RES..1
(2675 2900);
FORCEPROP 1 LAST VALUE 750
J 2
(2650 2800);
DISPLAY 0.510638 (2650 2800);
PAINT SKYBLUE (2650 2800);
FORCEPROP 1 LAST TOLERANCE 1%
J 0
(2675 2800);
DISPLAY 0.510638 (2675 2800);
PAINT SKYBLUE (2675 2800);
FORCEPROP 1 LAST WATTAGE 1/16W
J 2
(2425 2800);
DISPLAY 0.510638 (2425 2800);
PAINT SKYBLUE (2425 2800);
FORCEPROP 1 LAST MATERIAL CHIP
J 0
(2450 2800);
DISPLAY 0.510638 (2450 2800);
PAINT SKYBLUE (2450 2800);
FORCEPROP 1 LAST PACK_TYPE 0402LF
J 0
(2750 2800);
DISPLAY 0.510638 (2750 2800);
PAINT SKYBLUE (2750 2800);
FORCEPROP 1 LAST PART_NUMBER CS17502FB03
J 0
(2300 2925);
DISPLAY 0.510638 (2300 2925);
PAINT WHITE (2300 2925);
FORCEPROP 2 LAST CDS_LIB pure_quanta
J 0
(2675 2900);
DISPLAY INVISIBLE (2675 2900);
FORCEPROP 1 LAST PATH I23
J 0
(2625 3050);
DISPLAY 0.978723 (2625 3050);
PAINT WHITE (2625 3050);
DISPLAY INVISIBLE (2625 3050);
FORCEPROP 1 LAST LOCATION R599
J 0
(2625 2950);
DISPLAY 0.702128 (2625 2950);
PAINT YELLOW (2625 2950);
FORCEPROP 0 LAST $SEC 1
J 0
(2625 3000);
DISPLAY 0.680851 (2625 3000);
PAINT MONO (2625 3000);
DISPLAY INVISIBLE (2625 3000);
FORCEPROP 0 LAST CDS_SEC 1
J 0
(2625 3000);
DISPLAY 1.021277 (2625 3000);
DISPLAY INVISIBLE (2625 3000);
FORCEPROP 1 LASTPIN (2575 2900) $PN 1
J 0
(2587 2912);
DISPLAY 0.808511 (2587 2912);
PAINT WHITE (2587 2912);
DISPLAY INVISIBLE (2587 2912);
FORCEPROP 1 LASTPIN (2775 2900) $PN 2
J 0
(2737 2912);
DISPLAY 0.808511 (2737 2912);
PAINT WHITE (2737 2912);
DISPLAY INVISIBLE (2737 2912);
FORCEADD Q_RES..1
(2675 2600);
FORCEPROP 1 LAST VALUE 750
J 2
(2650 2500);
DISPLAY 0.510638 (2650 2500);
PAINT SKYBLUE (2650 2500);
FORCEPROP 1 LAST TOLERANCE 1%
J 0
(2675 2500);
DISPLAY 0.510638 (2675 2500);
PAINT SKYBLUE (2675 2500);
FORCEPROP 1 LAST WATTAGE 1/16W
J 2
(2425 2500);
DISPLAY 0.510638 (2425 2500);
PAINT SKYBLUE (2425 2500);
FORCEPROP 1 LAST MATERIAL CHIP
J 0
(2450 2500);
DISPLAY 0.510638 (2450 2500);
PAINT SKYBLUE (2450 2500);
FORCEPROP 1 LAST PACK_TYPE 0402LF
J 0
(2750 2500);
DISPLAY 0.510638 (2750 2500);
PAINT SKYBLUE (2750 2500);
FORCEPROP 1 LAST PART_NUMBER CS17502FB03
J 0
(2300 2625);
DISPLAY 0.510638 (2300 2625);
PAINT WHITE (2300 2625);
FORCEPROP 2 LAST CDS_LIB pure_quanta
J 0
(2675 2600);
DISPLAY INVISIBLE (2675 2600);
FORCEPROP 1 LAST PATH I25
J 0
(2625 2750);
DISPLAY 0.978723 (2625 2750);
PAINT WHITE (2625 2750);
DISPLAY INVISIBLE (2625 2750);
FORCEPROP 1 LAST LOCATION R600
J 0
(2625 2650);
DISPLAY 0.702128 (2625 2650);
PAINT YELLOW (2625 2650);
FORCEPROP 0 LAST $SEC 1
J 0
(2625 2700);
DISPLAY 0.680851 (2625 2700);
PAINT MONO (2625 2700);
DISPLAY INVISIBLE (2625 2700);
FORCEPROP 0 LAST CDS_SEC 1
J 0
(2625 2700);
DISPLAY 1.021277 (2625 2700);
DISPLAY INVISIBLE (2625 2700);
FORCEPROP 1 LASTPIN (2575 2600) $PN 1
J 0
(2587 2612);
DISPLAY 0.808511 (2587 2612);
PAINT WHITE (2587 2612);
DISPLAY INVISIBLE (2587 2612);
FORCEPROP 1 LASTPIN (2775 2600) $PN 2
J 0
(2737 2612);
DISPLAY 0.808511 (2737 2612);
PAINT WHITE (2737 2612);
DISPLAY INVISIBLE (2737 2612);
FORCEADD Q_RES..1
(2675 2300);
FORCEPROP 1 LAST VALUE 750
J 2
(2650 2200);
DISPLAY 0.510638 (2650 2200);
PAINT SKYBLUE (2650 2200);
FORCEPROP 1 LAST TOLERANCE 1%
J 0
(2675 2200);
DISPLAY 0.510638 (2675 2200);
PAINT SKYBLUE (2675 2200);
FORCEPROP 1 LAST WATTAGE 1/16W
J 2
(2425 2200);
DISPLAY 0.510638 (2425 2200);
PAINT SKYBLUE (2425 2200);
FORCEPROP 1 LAST MATERIAL CHIP
J 0
(2450 2200);
DISPLAY 0.510638 (2450 2200);
PAINT SKYBLUE (2450 2200);
FORCEPROP 1 LAST PACK_TYPE 0402LF
J 0
(2750 2200);
DISPLAY 0.510638 (2750 2200);
PAINT SKYBLUE (2750 2200);
FORCEPROP 1 LAST PART_NUMBER CS17502FB03
J 0
(2300 2325);
DISPLAY 0.510638 (2300 2325);
PAINT WHITE (2300 2325);
FORCEPROP 2 LAST CDS_LIB pure_quanta
J 0
(2675 2300);
DISPLAY INVISIBLE (2675 2300);
FORCEPROP 1 LAST PATH I31
J 0
(2625 2450);
DISPLAY 0.978723 (2625 2450);
PAINT WHITE (2625 2450);
DISPLAY INVISIBLE (2625 2450);
FORCEPROP 1 LAST LOCATION R601
J 0
(2625 2350);
DISPLAY 0.702128 (2625 2350);
PAINT YELLOW (2625 2350);
FORCEPROP 0 LAST $SEC 1
J 0
(2625 2400);
DISPLAY 0.680851 (2625 2400);
PAINT MONO (2625 2400);
DISPLAY INVISIBLE (2625 2400);
FORCEPROP 0 LAST CDS_SEC 1
J 0
(2625 2400);
DISPLAY 1.021277 (2625 2400);
DISPLAY INVISIBLE (2625 2400);
FORCEPROP 1 LASTPIN (2575 2300) $PN 1
J 0
(2587 2312);
DISPLAY 0.808511 (2587 2312);
PAINT WHITE (2587 2312);
DISPLAY INVISIBLE (2587 2312);
FORCEPROP 1 LASTPIN (2775 2300) $PN 2
J 0
(2737 2312);
DISPLAY 0.808511 (2737 2312);
PAINT WHITE (2737 2312);
DISPLAY INVISIBLE (2737 2312);
FORCEADD Q_RES..1
(2675 2000);
FORCEPROP 1 LAST VALUE 750
J 2
(2650 1900);
DISPLAY 0.510638 (2650 1900);
PAINT SKYBLUE (2650 1900);
FORCEPROP 1 LAST TOLERANCE 1%
J 0
(2675 1900);
DISPLAY 0.510638 (2675 1900);
PAINT SKYBLUE (2675 1900);
FORCEPROP 1 LAST WATTAGE 1/16W
J 2
(2425 1900);
DISPLAY 0.510638 (2425 1900);
PAINT SKYBLUE (2425 1900);
FORCEPROP 1 LAST MATERIAL CHIP
J 0
(2450 1900);
DISPLAY 0.510638 (2450 1900);
PAINT SKYBLUE (2450 1900);
FORCEPROP 1 LAST PACK_TYPE 0402LF
J 0
(2750 1900);
DISPLAY 0.510638 (2750 1900);
PAINT SKYBLUE (2750 1900);
FORCEPROP 1 LAST PART_NUMBER CS17502FB03
J 0
(2300 2025);
DISPLAY 0.510638 (2300 2025);
PAINT WHITE (2300 2025);
FORCEPROP 2 LAST CDS_LIB pure_quanta
J 0
(2675 2000);
DISPLAY INVISIBLE (2675 2000);
FORCEPROP 1 LAST PATH I33
J 0
(2625 2150);
DISPLAY 0.978723 (2625 2150);
PAINT WHITE (2625 2150);
DISPLAY INVISIBLE (2625 2150);
FORCEPROP 1 LAST LOCATION R602
J 0
(2625 2050);
DISPLAY 0.702128 (2625 2050);
PAINT YELLOW (2625 2050);
FORCEPROP 0 LAST $SEC 1
J 0
(2625 2100);
DISPLAY 0.680851 (2625 2100);
PAINT MONO (2625 2100);
DISPLAY INVISIBLE (2625 2100);
FORCEPROP 0 LAST CDS_SEC 1
J 0
(2625 2100);
DISPLAY 1.021277 (2625 2100);
DISPLAY INVISIBLE (2625 2100);
FORCEPROP 1 LASTPIN (2575 2000) $PN 1
J 0
(2587 2012);
DISPLAY 0.808511 (2587 2012);
PAINT WHITE (2587 2012);
DISPLAY INVISIBLE (2587 2012);
FORCEPROP 1 LASTPIN (2775 2000) $PN 2
J 0
(2737 2012);
DISPLAY 0.808511 (2737 2012);
PAINT WHITE (2737 2012);
DISPLAY INVISIBLE (2737 2012);
FORCEADD Q_RES..1
(2675 1700);
FORCEPROP 1 LAST VALUE 750
J 2
(2650 1600);
DISPLAY 0.510638 (2650 1600);
PAINT SKYBLUE (2650 1600);
FORCEPROP 1 LAST TOLERANCE 1%
J 0
(2675 1600);
DISPLAY 0.510638 (2675 1600);
PAINT SKYBLUE (2675 1600);
FORCEPROP 1 LAST WATTAGE 1/16W
J 2
(2425 1600);
DISPLAY 0.510638 (2425 1600);
PAINT SKYBLUE (2425 1600);
FORCEPROP 1 LAST MATERIAL CHIP
J 0
(2450 1600);
DISPLAY 0.510638 (2450 1600);
PAINT SKYBLUE (2450 1600);
FORCEPROP 1 LAST PACK_TYPE 0402LF
J 0
(2750 1600);
DISPLAY 0.510638 (2750 1600);
PAINT SKYBLUE (2750 1600);
FORCEPROP 1 LAST PART_NUMBER CS17502FB03
J 0
(2300 1725);
DISPLAY 0.510638 (2300 1725);
PAINT WHITE (2300 1725);
FORCEPROP 2 LAST CDS_LIB pure_quanta
J 0
(2675 1700);
DISPLAY INVISIBLE (2675 1700);
FORCEPROP 1 LAST PATH I35
J 0
(2625 1850);
DISPLAY 0.978723 (2625 1850);
PAINT WHITE (2625 1850);
DISPLAY INVISIBLE (2625 1850);
FORCEPROP 1 LAST LOCATION R603
J 0
(2625 1750);
DISPLAY 0.702128 (2625 1750);
PAINT YELLOW (2625 1750);
FORCEPROP 0 LAST $SEC 1
J 0
(2625 1800);
DISPLAY 0.680851 (2625 1800);
PAINT MONO (2625 1800);
DISPLAY INVISIBLE (2625 1800);
FORCEPROP 0 LAST CDS_SEC 1
J 0
(2625 1800);
DISPLAY 1.021277 (2625 1800);
DISPLAY INVISIBLE (2625 1800);
FORCEPROP 1 LASTPIN (2575 1700) $PN 1
J 0
(2587 1712);
DISPLAY 0.808511 (2587 1712);
PAINT WHITE (2587 1712);
DISPLAY INVISIBLE (2587 1712);
FORCEPROP 1 LASTPIN (2775 1700) $PN 2
J 0
(2737 1712);
DISPLAY 0.808511 (2737 1712);
PAINT WHITE (2737 1712);
DISPLAY INVISIBLE (2737 1712);
FORCEADD Q_RES..1
(2675 1400);
FORCEPROP 1 LAST VALUE 750
J 2
(2650 1300);
DISPLAY 0.510638 (2650 1300);
PAINT SKYBLUE (2650 1300);
FORCEPROP 1 LAST TOLERANCE 1%
J 0
(2675 1300);
DISPLAY 0.510638 (2675 1300);
PAINT SKYBLUE (2675 1300);
FORCEPROP 1 LAST WATTAGE 1/16W
J 2
(2425 1300);
DISPLAY 0.510638 (2425 1300);
PAINT SKYBLUE (2425 1300);
FORCEPROP 1 LAST MATERIAL CHIP
J 0
(2450 1300);
DISPLAY 0.510638 (2450 1300);
PAINT SKYBLUE (2450 1300);
FORCEPROP 1 LAST PACK_TYPE 0402LF
J 0
(2750 1300);
DISPLAY 0.510638 (2750 1300);
PAINT SKYBLUE (2750 1300);
FORCEPROP 1 LAST PART_NUMBER CS17502FB03
J 0
(2300 1425);
DISPLAY 0.510638 (2300 1425);
PAINT WHITE (2300 1425);
FORCEPROP 2 LAST CDS_LIB pure_quanta
J 0
(2675 1400);
DISPLAY INVISIBLE (2675 1400);
FORCEPROP 1 LAST PATH I37
J 0
(2625 1550);
DISPLAY 0.978723 (2625 1550);
PAINT WHITE (2625 1550);
DISPLAY INVISIBLE (2625 1550);
FORCEPROP 1 LAST LOCATION R604
J 0
(2625 1450);
DISPLAY 0.702128 (2625 1450);
PAINT YELLOW (2625 1450);
FORCEPROP 0 LAST $SEC 1
J 0
(2625 1500);
DISPLAY 0.680851 (2625 1500);
PAINT MONO (2625 1500);
DISPLAY INVISIBLE (2625 1500);
FORCEPROP 0 LAST CDS_SEC 1
J 0
(2625 1500);
DISPLAY 1.021277 (2625 1500);
DISPLAY INVISIBLE (2625 1500);
FORCEPROP 1 LASTPIN (2575 1400) $PN 1
J 0
(2587 1412);
DISPLAY 0.808511 (2587 1412);
PAINT WHITE (2587 1412);
DISPLAY INVISIBLE (2587 1412);
FORCEPROP 1 LASTPIN (2775 1400) $PN 2
J 0
(2737 1412);
DISPLAY 0.808511 (2737 1412);
PAINT WHITE (2737 1412);
DISPLAY INVISIBLE (2737 1412);
FORCEADD UNIVERSAL_GND..1
(5075 1175);
FORCEPROP 3 LASTPIN (5075 1225) SIG_NAME GND\g
J 0
(5085 1235);
DISPLAY 0.659574 (5085 1235);
PAINT MONO (5085 1235);
DISPLAY INVISIBLE (5085 1235);
FORCEPROP 2 LAST CDS_LIB logical_power
J 0
(5075 1175);
DISPLAY INVISIBLE (5075 1175);
FORCEPROP 1 LAST HDL_POWER GND
J 1
(5100 1100);
DISPLAY 0.702128 (5100 1100);
PAINT GREEN (5100 1100);
DISPLAY INVISIBLE (5100 1100);
FORCEPROP 1 LAST PATH I39
J 0
(5150 1175);
DISPLAY 0.872340 (5150 1175);
PAINT AQUA (5150 1175);
DISPLAY INVISIBLE (5150 1175);
FORCEADD OFFPAGE..1
(1475 3500);
FORCEPROP 2 LAST $XR0 13 
J 0
(1224 3500);
DISPLAY 0.638298 (1224 3500);
PAINT MONO (1224 3500);
FORCEPROP 2 LAST CDS_LIB standard
J 0
(1475 3500);
DISPLAY INVISIBLE (1475 3500);
FORCEPROP 1 LAST OFFPAGE TRUE
J 0
(1800 3375);
DISPLAY 0.872340 (1800 3375);
PAINT GREEN (1800 3375);
DISPLAY INVISIBLE (1800 3375);
FORCEPROP 1 LAST COMMENT_BODY TRUE
J 0
(1600 3400);
DISPLAY 0.872340 (1600 3400);
PAINT PEACH (1600 3400);
DISPLAY INVISIBLE (1600 3400);
FORCEPROP 2 LAST PATH I40
J 0
(1225 3550);
DISPLAY 0.680851 (1225 3550);
DISPLAY INVISIBLE (1225 3550);
FORCEADD OFFPAGE..1
(1475 3200);
FORCEPROP 2 LAST $XR0 13 
J 0
(1224 3200);
DISPLAY 0.638298 (1224 3200);
PAINT MONO (1224 3200);
FORCEPROP 2 LAST CDS_LIB standard
J 0
(1475 3200);
DISPLAY INVISIBLE (1475 3200);
FORCEPROP 1 LAST OFFPAGE TRUE
J 0
(1800 3075);
DISPLAY 0.872340 (1800 3075);
PAINT GREEN (1800 3075);
DISPLAY INVISIBLE (1800 3075);
FORCEPROP 1 LAST COMMENT_BODY TRUE
J 0
(1600 3100);
DISPLAY 0.872340 (1600 3100);
PAINT PEACH (1600 3100);
DISPLAY INVISIBLE (1600 3100);
FORCEPROP 2 LAST PATH I41
J 0
(1225 3250);
DISPLAY 0.680851 (1225 3250);
DISPLAY INVISIBLE (1225 3250);
FORCEADD OFFPAGE..1
(1475 2900);
FORCEPROP 2 LAST $XR0 13 
J 0
(1224 2900);
DISPLAY 0.638298 (1224 2900);
PAINT MONO (1224 2900);
FORCEPROP 2 LAST CDS_LIB standard
J 0
(1475 2900);
DISPLAY INVISIBLE (1475 2900);
FORCEPROP 1 LAST OFFPAGE TRUE
J 0
(1800 2775);
DISPLAY 0.872340 (1800 2775);
PAINT GREEN (1800 2775);
DISPLAY INVISIBLE (1800 2775);
FORCEPROP 1 LAST COMMENT_BODY TRUE
J 0
(1600 2800);
DISPLAY 0.872340 (1600 2800);
PAINT PEACH (1600 2800);
DISPLAY INVISIBLE (1600 2800);
FORCEPROP 2 LAST PATH I42
J 0
(1225 2950);
DISPLAY 0.680851 (1225 2950);
DISPLAY INVISIBLE (1225 2950);
FORCEADD OFFPAGE..1
(1475 2600);
FORCEPROP 2 LAST $XR0 13 
J 0
(1224 2600);
DISPLAY 0.638298 (1224 2600);
PAINT MONO (1224 2600);
FORCEPROP 2 LAST CDS_LIB standard
J 0
(1475 2600);
DISPLAY INVISIBLE (1475 2600);
FORCEPROP 1 LAST OFFPAGE TRUE
J 0
(1800 2475);
DISPLAY 0.872340 (1800 2475);
PAINT GREEN (1800 2475);
DISPLAY INVISIBLE (1800 2475);
FORCEPROP 1 LAST COMMENT_BODY TRUE
J 0
(1600 2500);
DISPLAY 0.872340 (1600 2500);
PAINT PEACH (1600 2500);
DISPLAY INVISIBLE (1600 2500);
FORCEPROP 2 LAST PATH I43
J 0
(1225 2650);
DISPLAY 0.680851 (1225 2650);
DISPLAY INVISIBLE (1225 2650);
FORCEADD OFFPAGE..1
(1475 2300);
FORCEPROP 2 LAST $XR0 13 
J 0
(1224 2300);
DISPLAY 0.638298 (1224 2300);
PAINT MONO (1224 2300);
FORCEPROP 2 LAST CDS_LIB standard
J 0
(1475 2300);
DISPLAY INVISIBLE (1475 2300);
FORCEPROP 1 LAST OFFPAGE TRUE
J 0
(1800 2175);
DISPLAY 0.872340 (1800 2175);
PAINT GREEN (1800 2175);
DISPLAY INVISIBLE (1800 2175);
FORCEPROP 1 LAST COMMENT_BODY TRUE
J 0
(1600 2200);
DISPLAY 0.872340 (1600 2200);
PAINT PEACH (1600 2200);
DISPLAY INVISIBLE (1600 2200);
FORCEPROP 2 LAST PATH I44
J 0
(1225 2350);
DISPLAY 0.680851 (1225 2350);
DISPLAY INVISIBLE (1225 2350);
FORCEADD OFFPAGE..1
(1475 2000);
FORCEPROP 2 LAST $XR0 13 
J 0
(1224 2000);
DISPLAY 0.638298 (1224 2000);
PAINT MONO (1224 2000);
FORCEPROP 2 LAST CDS_LIB standard
J 0
(1475 2000);
DISPLAY INVISIBLE (1475 2000);
FORCEPROP 1 LAST OFFPAGE TRUE
J 0
(1800 1875);
DISPLAY 0.872340 (1800 1875);
PAINT GREEN (1800 1875);
DISPLAY INVISIBLE (1800 1875);
FORCEPROP 1 LAST COMMENT_BODY TRUE
J 0
(1600 1900);
DISPLAY 0.872340 (1600 1900);
PAINT PEACH (1600 1900);
DISPLAY INVISIBLE (1600 1900);
FORCEPROP 2 LAST PATH I45
J 0
(1225 2050);
DISPLAY 0.680851 (1225 2050);
DISPLAY INVISIBLE (1225 2050);
FORCEADD OFFPAGE..1
(1475 1700);
FORCEPROP 2 LAST $XR0 13 
J 0
(1224 1700);
DISPLAY 0.638298 (1224 1700);
PAINT MONO (1224 1700);
FORCEPROP 2 LAST CDS_LIB standard
J 0
(1475 1700);
DISPLAY INVISIBLE (1475 1700);
FORCEPROP 1 LAST OFFPAGE TRUE
J 0
(1800 1575);
DISPLAY 0.872340 (1800 1575);
PAINT GREEN (1800 1575);
DISPLAY INVISIBLE (1800 1575);
FORCEPROP 1 LAST COMMENT_BODY TRUE
J 0
(1600 1600);
DISPLAY 0.872340 (1600 1600);
PAINT PEACH (1600 1600);
DISPLAY INVISIBLE (1600 1600);
FORCEPROP 2 LAST PATH I46
J 0
(1225 1750);
DISPLAY 0.680851 (1225 1750);
DISPLAY INVISIBLE (1225 1750);
FORCEADD OFFPAGE..1
(1475 1400);
FORCEPROP 2 LAST $XR0 13 
J 0
(1224 1400);
DISPLAY 0.638298 (1224 1400);
PAINT MONO (1224 1400);
FORCEPROP 2 LAST CDS_LIB standard
J 0
(1475 1400);
DISPLAY INVISIBLE (1475 1400);
FORCEPROP 1 LAST OFFPAGE TRUE
J 0
(1800 1275);
DISPLAY 0.872340 (1800 1275);
PAINT GREEN (1800 1275);
DISPLAY INVISIBLE (1800 1275);
FORCEPROP 1 LAST COMMENT_BODY TRUE
J 0
(1600 1300);
DISPLAY 0.872340 (1600 1300);
PAINT PEACH (1600 1300);
DISPLAY INVISIBLE (1600 1300);
FORCEPROP 2 LAST PATH I47
J 0
(1225 1450);
DISPLAY 0.680851 (1225 1450);
DISPLAY INVISIBLE (1225 1450);
FORCEADD Q_RES..1
R 2
(1600 3650);
FORCEPROP 1 LAST VALUE 0
J 0
(1650 3625);
DISPLAY 0.510638 (1650 3625);
PAINT SKYBLUE (1650 3625);
FORCEPROP 1 LAST TOLERANCE 5%
J 2
(1750 3625);
DISPLAY 0.510638 (1750 3625);
PAINT SKYBLUE (1750 3625);
FORCEPROP 1 LAST WATTAGE 1/16W
J 0
(1900 3625);
DISPLAY 0.510638 (1900 3625);
PAINT SKYBLUE (1900 3625);
FORCEPROP 1 LAST MATERIAL CHIP
J 2
(1875 3625);
DISPLAY 0.510638 (1875 3625);
PAINT SKYBLUE (1875 3625);
FORCEPROP 1 LAST PACK_TYPE 0402LF
J 2
(2200 3625);
DISPLAY 0.510638 (2200 3625);
PAINT SKYBLUE (2200 3625);
FORCEPROP 2 LAST CDS_LIB pure_quanta
J 0
(1600 3650);
DISPLAY INVISIBLE (1600 3650);
FORCEPROP 1 LAST PATH I48
J 2
(1650 3800);
DISPLAY 0.978723 (1650 3800);
PAINT WHITE (1650 3800);
DISPLAY INVISIBLE (1650 3800);
FORCEPROP 1 LAST PART_NUMBER CS00002JB13
J 2
(1850 3675);
DISPLAY 0.510638 (1850 3675);
PAINT WHITE (1850 3675);
DISPLAY INVISIBLE (1850 3675);
FORCEPROP 1 LAST LOCATION R669
J 2
(1550 3650);
DISPLAY 0.702128 (1550 3650);
PAINT YELLOW (1550 3650);
FORCEPROP 0 LAST $SEC 1
J 0
(1550 3700);
DISPLAY 0.680851 (1550 3700);
PAINT MONO (1550 3700);
DISPLAY INVISIBLE (1550 3700);
FORCEPROP 0 LAST CDS_SEC 1
J 0
(1550 3700);
DISPLAY 1.021277 (1550 3700);
DISPLAY INVISIBLE (1550 3700);
FORCEPROP 1 LASTPIN (1700 3650) $PN 1
J 2
(1688 3662);
DISPLAY 0.808511 (1688 3662);
PAINT WHITE (1688 3662);
DISPLAY INVISIBLE (1688 3662);
FORCEPROP 1 LASTPIN (1500 3650) $PN 2
J 2
(1538 3662);
DISPLAY 0.808511 (1538 3662);
PAINT WHITE (1538 3662);
DISPLAY INVISIBLE (1538 3662);
FORCEADD OFFPAGE..5
(375 3650);
FORCEPROP 2 LAST $XR0 28 
J 0
(151 3650);
DISPLAY 0.638298 (151 3650);
PAINT MONO (151 3650);
FORCEPROP 2 LAST CDS_LIB standard
J 0
(375 3650);
DISPLAY INVISIBLE (375 3650);
FORCEPROP 1 LAST OFFPAGE TRUE
J 0
(700 3525);
DISPLAY 0.872340 (700 3525);
DISPLAY INVISIBLE (700 3525);
FORCEPROP 1 LAST COMMENT_BODY TRUE
J 0
(475 3575);
DISPLAY 0.872340 (475 3575);
PAINT GREEN (475 3575);
DISPLAY INVISIBLE (475 3575);
FORCEPROP 2 LAST PATH I49
J 0
(125 3700);
DISPLAY 0.680851 (125 3700);
DISPLAY INVISIBLE (125 3700);
FORCEADD Q_LED..1
(3875 3500);
FORCEPROP 2 LAST PACK_TYPE SMLF
J 0
(3650 3575);
DISPLAY 0.510638 (3650 3575);
PAINT SKYBLUE (3650 3575);
FORCEPROP 1 LAST PART_NUMBER BERD0034Z07
J 0
(3850 3575);
DISPLAY 0.510638 (3850 3575);
PAINT WHITE (3850 3575);
FORCEPROP 1 LAST MATERIAL IC
J 0
(3775 3580);
DISPLAY 0.510638 (3775 3580);
PAINT SKYBLUE (3775 3580);
FORCEPROP 2 LAST COLOR LED_RED
J 0
(3950 3625);
DISPLAY 0.808511 (3950 3625);
PAINT GREEN (3950 3625);
FORCEPROP 1 LAST NEEDS_NO_SIZE TRUE
J 0
(3875 3500);
DISPLAY 0.468085 (3875 3500);
PAINT GREEN (3875 3500);
DISPLAY INVISIBLE (3875 3500);
FORCEPROP 0 LAST MANUF_PN 19-217/R6C-P1Q2/3T
J 0
(3775 3775);
DISPLAY 0.808511 (3775 3775);
DISPLAY INVISIBLE (3775 3775);
FORCEPROP 2 LAST CDS_LIB pure_quanta
J 0
(3875 3500);
DISPLAY INVISIBLE (3875 3500);
FORCEPROP 1 LAST PATH I5
J 0
(4000 3580);
DISPLAY 0.723404 (4000 3580);
PAINT GREEN (4000 3580);
DISPLAY INVISIBLE (4000 3580);
FORCEPROP 1 LAST LOCATION D7
J 0
(3575 3575);
DISPLAY 0.702128 (3575 3575);
PAINT AQUA (3575 3575);
FORCEPROP 0 LASTPIN (3725 3500) $PN A
J 2
(3715 3510);
DISPLAY 0.680851 (3715 3510);
PAINT MONO (3715 3510);
FORCEPROP 0 LASTPIN (4025 3500) $PN C
J 0
(4035 3510);
DISPLAY 0.680851 (4035 3510);
PAINT MONO (4035 3510);
FORCEPROP 0 LAST $SEC 1
J 0
(3950 3675);
DISPLAY 0.680851 (3950 3675);
PAINT MONO (3950 3675);
DISPLAY INVISIBLE (3950 3675);
FORCEPROP 0 LAST CDS_SEC 1
J 0
(3950 3675);
DISPLAY 1.021277 (3950 3675);
DISPLAY INVISIBLE (3950 3675);
FORCEADD Q_RES..1
R 2
(1600 3350);
FORCEPROP 1 LAST VALUE 0
J 0
(1650 3325);
DISPLAY 0.510638 (1650 3325);
PAINT SKYBLUE (1650 3325);
FORCEPROP 1 LAST TOLERANCE 5%
J 2
(1750 3325);
DISPLAY 0.510638 (1750 3325);
PAINT SKYBLUE (1750 3325);
FORCEPROP 1 LAST WATTAGE 1/16W
J 0
(1900 3325);
DISPLAY 0.510638 (1900 3325);
PAINT SKYBLUE (1900 3325);
FORCEPROP 1 LAST MATERIAL CHIP
J 2
(1875 3325);
DISPLAY 0.510638 (1875 3325);
PAINT SKYBLUE (1875 3325);
FORCEPROP 1 LAST PACK_TYPE 0402LF
J 2
(2200 3325);
DISPLAY 0.510638 (2200 3325);
PAINT SKYBLUE (2200 3325);
FORCEPROP 2 LAST CDS_LIB pure_quanta
J 0
(1600 3350);
DISPLAY INVISIBLE (1600 3350);
FORCEPROP 1 LAST PATH I50
J 2
(1650 3500);
DISPLAY 0.978723 (1650 3500);
PAINT WHITE (1650 3500);
DISPLAY INVISIBLE (1650 3500);
FORCEPROP 1 LAST PART_NUMBER CS00002JB13
J 2
(1850 3375);
DISPLAY 0.510638 (1850 3375);
PAINT WHITE (1850 3375);
DISPLAY INVISIBLE (1850 3375);
FORCEPROP 1 LAST LOCATION R674
J 2
(1550 3350);
DISPLAY 0.702128 (1550 3350);
PAINT YELLOW (1550 3350);
FORCEPROP 0 LAST $SEC 1
J 0
(1550 3400);
DISPLAY 0.680851 (1550 3400);
PAINT MONO (1550 3400);
DISPLAY INVISIBLE (1550 3400);
FORCEPROP 0 LAST CDS_SEC 1
J 0
(1550 3400);
DISPLAY 1.021277 (1550 3400);
DISPLAY INVISIBLE (1550 3400);
FORCEPROP 1 LASTPIN (1700 3350) $PN 1
J 2
(1688 3362);
DISPLAY 0.808511 (1688 3362);
PAINT WHITE (1688 3362);
DISPLAY INVISIBLE (1688 3362);
FORCEPROP 1 LASTPIN (1500 3350) $PN 2
J 2
(1538 3362);
DISPLAY 0.808511 (1538 3362);
PAINT WHITE (1538 3362);
DISPLAY INVISIBLE (1538 3362);
FORCEADD OFFPAGE..5
(375 3350);
FORCEPROP 2 LAST $XR0 28 
J 0
(151 3350);
DISPLAY 0.638298 (151 3350);
PAINT MONO (151 3350);
FORCEPROP 2 LAST CDS_LIB standard
J 0
(375 3350);
DISPLAY INVISIBLE (375 3350);
FORCEPROP 1 LAST OFFPAGE TRUE
J 0
(700 3225);
DISPLAY 0.872340 (700 3225);
DISPLAY INVISIBLE (700 3225);
FORCEPROP 1 LAST COMMENT_BODY TRUE
J 0
(475 3275);
DISPLAY 0.872340 (475 3275);
PAINT GREEN (475 3275);
DISPLAY INVISIBLE (475 3275);
FORCEPROP 2 LAST PATH I51
J 0
(425 3425);
DISPLAY 0.680851 (425 3425);
DISPLAY INVISIBLE (425 3425);
FORCEADD Q_RES..1
R 2
(1600 3050);
FORCEPROP 1 LAST VALUE 0
J 0
(1650 3025);
DISPLAY 0.510638 (1650 3025);
PAINT SKYBLUE (1650 3025);
FORCEPROP 1 LAST TOLERANCE 5%
J 2
(1750 3025);
DISPLAY 0.510638 (1750 3025);
PAINT SKYBLUE (1750 3025);
FORCEPROP 1 LAST WATTAGE 1/16W
J 0
(1900 3025);
DISPLAY 0.510638 (1900 3025);
PAINT SKYBLUE (1900 3025);
FORCEPROP 1 LAST MATERIAL CHIP
J 2
(1875 3025);
DISPLAY 0.510638 (1875 3025);
PAINT SKYBLUE (1875 3025);
FORCEPROP 1 LAST PACK_TYPE 0402LF
J 2
(2200 3025);
DISPLAY 0.510638 (2200 3025);
PAINT SKYBLUE (2200 3025);
FORCEPROP 2 LAST CDS_LIB pure_quanta
J 0
(1600 3050);
DISPLAY INVISIBLE (1600 3050);
FORCEPROP 1 LAST PATH I52
J 2
(1650 3200);
DISPLAY 0.978723 (1650 3200);
PAINT WHITE (1650 3200);
DISPLAY INVISIBLE (1650 3200);
FORCEPROP 1 LAST PART_NUMBER CS00002JB13
J 2
(1850 3075);
DISPLAY 0.510638 (1850 3075);
PAINT WHITE (1850 3075);
DISPLAY INVISIBLE (1850 3075);
FORCEPROP 1 LAST LOCATION R676
J 2
(1550 3050);
DISPLAY 0.702128 (1550 3050);
PAINT YELLOW (1550 3050);
FORCEPROP 0 LAST $SEC 1
J 0
(1550 3100);
DISPLAY 0.680851 (1550 3100);
PAINT MONO (1550 3100);
DISPLAY INVISIBLE (1550 3100);
FORCEPROP 0 LAST CDS_SEC 1
J 0
(1550 3100);
DISPLAY 1.021277 (1550 3100);
DISPLAY INVISIBLE (1550 3100);
FORCEPROP 1 LASTPIN (1700 3050) $PN 1
J 2
(1688 3062);
DISPLAY 0.808511 (1688 3062);
PAINT WHITE (1688 3062);
DISPLAY INVISIBLE (1688 3062);
FORCEPROP 1 LASTPIN (1500 3050) $PN 2
J 2
(1538 3062);
DISPLAY 0.808511 (1538 3062);
PAINT WHITE (1538 3062);
DISPLAY INVISIBLE (1538 3062);
FORCEADD OFFPAGE..5
(375 3050);
FORCEPROP 2 LAST $XR0 28 
J 0
(151 3050);
DISPLAY 0.638298 (151 3050);
PAINT MONO (151 3050);
FORCEPROP 2 LAST CDS_LIB standard
J 0
(375 3050);
DISPLAY INVISIBLE (375 3050);
FORCEPROP 1 LAST OFFPAGE TRUE
J 0
(700 2925);
DISPLAY 0.872340 (700 2925);
DISPLAY INVISIBLE (700 2925);
FORCEPROP 1 LAST COMMENT_BODY TRUE
J 0
(475 2975);
DISPLAY 0.872340 (475 2975);
PAINT GREEN (475 2975);
DISPLAY INVISIBLE (475 2975);
FORCEPROP 2 LAST PATH I53
J 0
(425 3125);
DISPLAY 0.680851 (425 3125);
DISPLAY INVISIBLE (425 3125);
FORCEADD Q_RES..1
R 2
(1600 2750);
FORCEPROP 1 LAST VALUE 0
J 0
(1650 2725);
DISPLAY 0.510638 (1650 2725);
PAINT SKYBLUE (1650 2725);
FORCEPROP 1 LAST TOLERANCE 5%
J 2
(1750 2725);
DISPLAY 0.510638 (1750 2725);
PAINT SKYBLUE (1750 2725);
FORCEPROP 1 LAST WATTAGE 1/16W
J 0
(1900 2725);
DISPLAY 0.510638 (1900 2725);
PAINT SKYBLUE (1900 2725);
FORCEPROP 1 LAST MATERIAL CHIP
J 2
(1875 2725);
DISPLAY 0.510638 (1875 2725);
PAINT SKYBLUE (1875 2725);
FORCEPROP 1 LAST PACK_TYPE 0402LF
J 2
(2200 2725);
DISPLAY 0.510638 (2200 2725);
PAINT SKYBLUE (2200 2725);
FORCEPROP 2 LAST CDS_LIB pure_quanta
J 0
(1600 2750);
DISPLAY INVISIBLE (1600 2750);
FORCEPROP 1 LAST PATH I54
J 2
(1650 2900);
DISPLAY 0.978723 (1650 2900);
PAINT WHITE (1650 2900);
DISPLAY INVISIBLE (1650 2900);
FORCEPROP 1 LAST PART_NUMBER CS00002JB13
J 2
(1850 2775);
DISPLAY 0.510638 (1850 2775);
PAINT WHITE (1850 2775);
DISPLAY INVISIBLE (1850 2775);
FORCEPROP 1 LAST LOCATION R695
J 2
(1550 2750);
DISPLAY 0.702128 (1550 2750);
PAINT YELLOW (1550 2750);
FORCEPROP 0 LAST $SEC 1
J 0
(1550 2800);
DISPLAY 0.680851 (1550 2800);
PAINT MONO (1550 2800);
DISPLAY INVISIBLE (1550 2800);
FORCEPROP 0 LAST CDS_SEC 1
J 0
(1550 2800);
DISPLAY 1.021277 (1550 2800);
DISPLAY INVISIBLE (1550 2800);
FORCEPROP 1 LASTPIN (1700 2750) $PN 1
J 2
(1688 2762);
DISPLAY 0.808511 (1688 2762);
PAINT WHITE (1688 2762);
DISPLAY INVISIBLE (1688 2762);
FORCEPROP 1 LASTPIN (1500 2750) $PN 2
J 2
(1538 2762);
DISPLAY 0.808511 (1538 2762);
PAINT WHITE (1538 2762);
DISPLAY INVISIBLE (1538 2762);
FORCEADD OFFPAGE..5
(375 2750);
FORCEPROP 2 LAST $XR0 28 
J 0
(151 2750);
DISPLAY 0.638298 (151 2750);
PAINT MONO (151 2750);
FORCEPROP 2 LAST CDS_LIB standard
J 0
(375 2750);
DISPLAY INVISIBLE (375 2750);
FORCEPROP 1 LAST OFFPAGE TRUE
J 0
(700 2625);
DISPLAY 0.872340 (700 2625);
DISPLAY INVISIBLE (700 2625);
FORCEPROP 1 LAST COMMENT_BODY TRUE
J 0
(475 2675);
DISPLAY 0.872340 (475 2675);
PAINT GREEN (475 2675);
DISPLAY INVISIBLE (475 2675);
FORCEPROP 2 LAST PATH I55
J 0
(425 2825);
DISPLAY 0.680851 (425 2825);
DISPLAY INVISIBLE (425 2825);
FORCEADD Q_RES..1
R 2
(1600 2450);
FORCEPROP 1 LAST VALUE 0
J 0
(1650 2425);
DISPLAY 0.510638 (1650 2425);
PAINT SKYBLUE (1650 2425);
FORCEPROP 1 LAST TOLERANCE 5%
J 2
(1750 2425);
DISPLAY 0.510638 (1750 2425);
PAINT SKYBLUE (1750 2425);
FORCEPROP 1 LAST WATTAGE 1/16W
J 0
(1900 2425);
DISPLAY 0.510638 (1900 2425);
PAINT SKYBLUE (1900 2425);
FORCEPROP 1 LAST MATERIAL CHIP
J 2
(1875 2425);
DISPLAY 0.510638 (1875 2425);
PAINT SKYBLUE (1875 2425);
FORCEPROP 1 LAST PACK_TYPE 0402LF
J 2
(2200 2425);
DISPLAY 0.510638 (2200 2425);
PAINT SKYBLUE (2200 2425);
FORCEPROP 2 LAST CDS_LIB pure_quanta
J 0
(1600 2450);
DISPLAY INVISIBLE (1600 2450);
FORCEPROP 1 LAST PATH I56
J 2
(1650 2600);
DISPLAY 0.978723 (1650 2600);
PAINT WHITE (1650 2600);
DISPLAY INVISIBLE (1650 2600);
FORCEPROP 1 LAST PART_NUMBER CS00002JB13
J 2
(1850 2475);
DISPLAY 0.510638 (1850 2475);
PAINT WHITE (1850 2475);
DISPLAY INVISIBLE (1850 2475);
FORCEPROP 1 LAST LOCATION R696
J 2
(1550 2450);
DISPLAY 0.702128 (1550 2450);
PAINT YELLOW (1550 2450);
FORCEPROP 0 LAST $SEC 1
J 0
(1550 2500);
DISPLAY 0.680851 (1550 2500);
PAINT MONO (1550 2500);
DISPLAY INVISIBLE (1550 2500);
FORCEPROP 0 LAST CDS_SEC 1
J 0
(1550 2500);
DISPLAY 1.021277 (1550 2500);
DISPLAY INVISIBLE (1550 2500);
FORCEPROP 1 LASTPIN (1700 2450) $PN 1
J 2
(1688 2462);
DISPLAY 0.808511 (1688 2462);
PAINT WHITE (1688 2462);
DISPLAY INVISIBLE (1688 2462);
FORCEPROP 1 LASTPIN (1500 2450) $PN 2
J 2
(1538 2462);
DISPLAY 0.808511 (1538 2462);
PAINT WHITE (1538 2462);
DISPLAY INVISIBLE (1538 2462);
FORCEADD OFFPAGE..5
(375 2450);
FORCEPROP 2 LAST $XR0 28 
J 0
(151 2450);
DISPLAY 0.638298 (151 2450);
PAINT MONO (151 2450);
FORCEPROP 2 LAST CDS_LIB standard
J 0
(375 2450);
DISPLAY INVISIBLE (375 2450);
FORCEPROP 1 LAST OFFPAGE TRUE
J 0
(700 2325);
DISPLAY 0.872340 (700 2325);
DISPLAY INVISIBLE (700 2325);
FORCEPROP 1 LAST COMMENT_BODY TRUE
J 0
(475 2375);
DISPLAY 0.872340 (475 2375);
PAINT GREEN (475 2375);
DISPLAY INVISIBLE (475 2375);
FORCEPROP 2 LAST PATH I57
J 0
(425 2525);
DISPLAY 0.680851 (425 2525);
DISPLAY INVISIBLE (425 2525);
FORCEADD Q_RES..1
R 2
(1600 2150);
FORCEPROP 1 LAST VALUE 0
J 0
(1650 2125);
DISPLAY 0.510638 (1650 2125);
PAINT SKYBLUE (1650 2125);
FORCEPROP 1 LAST TOLERANCE 5%
J 2
(1750 2125);
DISPLAY 0.510638 (1750 2125);
PAINT SKYBLUE (1750 2125);
FORCEPROP 1 LAST WATTAGE 1/16W
J 0
(1900 2125);
DISPLAY 0.510638 (1900 2125);
PAINT SKYBLUE (1900 2125);
FORCEPROP 1 LAST MATERIAL CHIP
J 2
(1875 2125);
DISPLAY 0.510638 (1875 2125);
PAINT SKYBLUE (1875 2125);
FORCEPROP 1 LAST PACK_TYPE 0402LF
J 2
(2200 2125);
DISPLAY 0.510638 (2200 2125);
PAINT SKYBLUE (2200 2125);
FORCEPROP 2 LAST CDS_LIB pure_quanta
J 0
(1600 2150);
DISPLAY INVISIBLE (1600 2150);
FORCEPROP 1 LAST PATH I58
J 2
(1650 2300);
DISPLAY 0.978723 (1650 2300);
PAINT WHITE (1650 2300);
DISPLAY INVISIBLE (1650 2300);
FORCEPROP 1 LAST PART_NUMBER CS00002JB13
J 2
(1850 2175);
DISPLAY 0.510638 (1850 2175);
PAINT WHITE (1850 2175);
DISPLAY INVISIBLE (1850 2175);
FORCEPROP 1 LAST LOCATION R697
J 2
(1550 2150);
DISPLAY 0.702128 (1550 2150);
PAINT YELLOW (1550 2150);
FORCEPROP 0 LAST $SEC 1
J 0
(1550 2200);
DISPLAY 0.680851 (1550 2200);
PAINT MONO (1550 2200);
DISPLAY INVISIBLE (1550 2200);
FORCEPROP 0 LAST CDS_SEC 1
J 0
(1550 2200);
DISPLAY 1.021277 (1550 2200);
DISPLAY INVISIBLE (1550 2200);
FORCEPROP 1 LASTPIN (1700 2150) $PN 1
J 2
(1688 2162);
DISPLAY 0.808511 (1688 2162);
PAINT WHITE (1688 2162);
DISPLAY INVISIBLE (1688 2162);
FORCEPROP 1 LASTPIN (1500 2150) $PN 2
J 2
(1538 2162);
DISPLAY 0.808511 (1538 2162);
PAINT WHITE (1538 2162);
DISPLAY INVISIBLE (1538 2162);
FORCEADD OFFPAGE..5
(375 2150);
FORCEPROP 2 LAST $XR0 28 
J 0
(151 2150);
DISPLAY 0.638298 (151 2150);
PAINT MONO (151 2150);
FORCEPROP 2 LAST CDS_LIB standard
J 0
(375 2150);
DISPLAY INVISIBLE (375 2150);
FORCEPROP 1 LAST OFFPAGE TRUE
J 0
(700 2025);
DISPLAY 0.872340 (700 2025);
DISPLAY INVISIBLE (700 2025);
FORCEPROP 1 LAST COMMENT_BODY TRUE
J 0
(475 2075);
DISPLAY 0.872340 (475 2075);
PAINT GREEN (475 2075);
DISPLAY INVISIBLE (475 2075);
FORCEPROP 2 LAST PATH I59
J 0
(425 2225);
DISPLAY 0.680851 (425 2225);
DISPLAY INVISIBLE (425 2225);
FORCEADD Q_RES..1
R 2
(1600 1850);
FORCEPROP 1 LAST VALUE 0
J 0
(1650 1825);
DISPLAY 0.510638 (1650 1825);
PAINT SKYBLUE (1650 1825);
FORCEPROP 1 LAST TOLERANCE 5%
J 2
(1750 1825);
DISPLAY 0.510638 (1750 1825);
PAINT SKYBLUE (1750 1825);
FORCEPROP 1 LAST MATERIAL CHIP
J 2
(1875 1825);
DISPLAY 0.510638 (1875 1825);
PAINT SKYBLUE (1875 1825);
FORCEPROP 1 LAST WATTAGE 1/16W
J 0
(1900 1825);
DISPLAY 0.510638 (1900 1825);
PAINT SKYBLUE (1900 1825);
FORCEPROP 1 LAST PACK_TYPE 0402LF
J 2
(2200 1825);
DISPLAY 0.510638 (2200 1825);
PAINT SKYBLUE (2200 1825);
FORCEPROP 2 LAST CDS_LIB pure_quanta
J 0
(1600 1850);
DISPLAY INVISIBLE (1600 1850);
FORCEPROP 1 LAST PATH I60
J 2
(1650 2000);
DISPLAY 0.978723 (1650 2000);
PAINT WHITE (1650 2000);
DISPLAY INVISIBLE (1650 2000);
FORCEPROP 1 LAST PART_NUMBER CS00002JB13
J 2
(1850 1875);
DISPLAY 0.510638 (1850 1875);
PAINT WHITE (1850 1875);
DISPLAY INVISIBLE (1850 1875);
FORCEPROP 1 LAST LOCATION R698
J 2
(1550 1850);
DISPLAY 0.702128 (1550 1850);
PAINT YELLOW (1550 1850);
FORCEPROP 0 LAST $SEC 1
J 0
(1550 1900);
DISPLAY 0.680851 (1550 1900);
PAINT MONO (1550 1900);
DISPLAY INVISIBLE (1550 1900);
FORCEPROP 0 LAST CDS_SEC 1
J 0
(1550 1900);
DISPLAY 1.021277 (1550 1900);
DISPLAY INVISIBLE (1550 1900);
FORCEPROP 1 LASTPIN (1700 1850) $PN 1
J 2
(1688 1862);
DISPLAY 0.808511 (1688 1862);
PAINT WHITE (1688 1862);
DISPLAY INVISIBLE (1688 1862);
FORCEPROP 1 LASTPIN (1500 1850) $PN 2
J 2
(1538 1862);
DISPLAY 0.808511 (1538 1862);
PAINT WHITE (1538 1862);
DISPLAY INVISIBLE (1538 1862);
FORCEADD OFFPAGE..5
(375 1850);
FORCEPROP 2 LAST $XR0 28 
J 0
(151 1850);
DISPLAY 0.638298 (151 1850);
PAINT MONO (151 1850);
FORCEPROP 2 LAST CDS_LIB standard
J 0
(375 1850);
DISPLAY INVISIBLE (375 1850);
FORCEPROP 1 LAST OFFPAGE TRUE
J 0
(700 1725);
DISPLAY 0.872340 (700 1725);
DISPLAY INVISIBLE (700 1725);
FORCEPROP 1 LAST COMMENT_BODY TRUE
J 0
(475 1775);
DISPLAY 0.872340 (475 1775);
PAINT GREEN (475 1775);
DISPLAY INVISIBLE (475 1775);
FORCEPROP 2 LAST PATH I61
J 0
(425 1925);
DISPLAY 0.680851 (425 1925);
DISPLAY INVISIBLE (425 1925);
FORCEADD Q_RES..1
R 2
(1600 1550);
FORCEPROP 1 LAST VALUE 0
J 0
(1650 1525);
DISPLAY 0.510638 (1650 1525);
PAINT SKYBLUE (1650 1525);
FORCEPROP 1 LAST TOLERANCE 5%
J 2
(1750 1525);
DISPLAY 0.510638 (1750 1525);
PAINT SKYBLUE (1750 1525);
FORCEPROP 1 LAST WATTAGE 1/16W
J 0
(1900 1525);
DISPLAY 0.510638 (1900 1525);
PAINT SKYBLUE (1900 1525);
FORCEPROP 1 LAST MATERIAL CHIP
J 2
(1875 1525);
DISPLAY 0.510638 (1875 1525);
PAINT SKYBLUE (1875 1525);
FORCEPROP 1 LAST PACK_TYPE 0402LF
J 2
(2200 1525);
DISPLAY 0.510638 (2200 1525);
PAINT SKYBLUE (2200 1525);
FORCEPROP 2 LAST CDS_LIB pure_quanta
J 0
(1600 1550);
DISPLAY INVISIBLE (1600 1550);
FORCEPROP 1 LAST PATH I62
J 2
(1650 1700);
DISPLAY 0.978723 (1650 1700);
PAINT WHITE (1650 1700);
DISPLAY INVISIBLE (1650 1700);
FORCEPROP 1 LAST PART_NUMBER CS00002JB13
J 2
(1850 1575);
DISPLAY 0.510638 (1850 1575);
PAINT WHITE (1850 1575);
DISPLAY INVISIBLE (1850 1575);
FORCEPROP 1 LAST LOCATION R700
J 2
(1550 1550);
DISPLAY 0.702128 (1550 1550);
PAINT YELLOW (1550 1550);
FORCEPROP 0 LAST $SEC 1
J 0
(1550 1600);
DISPLAY 0.680851 (1550 1600);
PAINT MONO (1550 1600);
DISPLAY INVISIBLE (1550 1600);
FORCEPROP 0 LAST CDS_SEC 1
J 0
(1550 1600);
DISPLAY 1.021277 (1550 1600);
DISPLAY INVISIBLE (1550 1600);
FORCEPROP 1 LASTPIN (1700 1550) $PN 1
J 2
(1688 1562);
DISPLAY 0.808511 (1688 1562);
PAINT WHITE (1688 1562);
DISPLAY INVISIBLE (1688 1562);
FORCEPROP 1 LASTPIN (1500 1550) $PN 2
J 2
(1538 1562);
DISPLAY 0.808511 (1538 1562);
PAINT WHITE (1538 1562);
DISPLAY INVISIBLE (1538 1562);
FORCEADD OFFPAGE..5
(375 1550);
FORCEPROP 2 LAST $XR0 28 
J 0
(151 1550);
DISPLAY 0.638298 (151 1550);
PAINT MONO (151 1550);
FORCEPROP 2 LAST CDS_LIB standard
J 0
(375 1550);
DISPLAY INVISIBLE (375 1550);
FORCEPROP 1 LAST OFFPAGE TRUE
J 0
(700 1425);
DISPLAY 0.872340 (700 1425);
DISPLAY INVISIBLE (700 1425);
FORCEPROP 1 LAST COMMENT_BODY TRUE
J 0
(475 1475);
DISPLAY 0.872340 (475 1475);
PAINT GREEN (475 1475);
DISPLAY INVISIBLE (475 1475);
FORCEPROP 2 LAST PATH I63
J 0
(425 1625);
DISPLAY 0.680851 (425 1625);
DISPLAY INVISIBLE (425 1625);
FORCEADD Q_LED..1
(3875 1400);
FORCEPROP 2 LAST PACK_TYPE SMLF
J 0
(3675 1475);
DISPLAY 0.510638 (3675 1475);
PAINT SKYBLUE (3675 1475);
FORCEPROP 1 LAST MATERIAL IC
J 0
(3775 1480);
DISPLAY 0.510638 (3775 1480);
PAINT SKYBLUE (3775 1480);
FORCEPROP 2 LAST COLOR LED_GREEN
J 0
(3975 1525);
DISPLAY 0.808511 (3975 1525);
PAINT GREEN (3975 1525);
FORCEPROP 1 LAST PART_NUMBER BEGR0278Z00
J 0
(3850 1475);
DISPLAY 0.510638 (3850 1475);
PAINT WHITE (3850 1475);
FORCEPROP 2 LAST CDS_LIB pure_quanta
J 0
(3875 1400);
DISPLAY INVISIBLE (3875 1400);
FORCEPROP 1 LAST NEEDS_NO_SIZE TRUE
J 0
(3875 1400);
DISPLAY 0.468085 (3875 1400);
PAINT GREEN (3875 1400);
DISPLAY INVISIBLE (3875 1400);
FORCEPROP 0 LAST MANUF_PN 19-213/GVC-AMNB/3T
J 0
(3775 1675);
DISPLAY 0.808511 (3775 1675);
DISPLAY INVISIBLE (3775 1675);
FORCEPROP 1 LAST PATH I7
J 0
(4000 1480);
DISPLAY 0.723404 (4000 1480);
PAINT GREEN (4000 1480);
DISPLAY INVISIBLE (4000 1480);
FORCEPROP 1 LAST LOCATION D0
J 0
(3775 1585);
DISPLAY 0.702128 (3775 1585);
PAINT AQUA (3775 1585);
FORCEPROP 0 LASTPIN (3725 1400) $PN A
J 2
(3715 1410);
DISPLAY 0.680851 (3715 1410);
PAINT MONO (3715 1410);
FORCEPROP 0 LASTPIN (4025 1400) $PN C
J 0
(4035 1410);
DISPLAY 0.680851 (4035 1410);
PAINT MONO (4035 1410);
FORCEPROP 0 LAST $SEC 1
J 0
(3775 1625);
DISPLAY 0.680851 (3775 1625);
PAINT MONO (3775 1625);
DISPLAY INVISIBLE (3775 1625);
FORCEPROP 0 LAST CDS_SEC 1
J 0
(3775 1625);
DISPLAY 1.021277 (3775 1625);
DISPLAY INVISIBLE (3775 1625);
FORCEADD Q_LED..1
(3875 1700);
FORCEPROP 2 LAST PACK_TYPE SMLF
J 0
(3675 1775);
DISPLAY 0.510638 (3675 1775);
PAINT SKYBLUE (3675 1775);
FORCEPROP 1 LAST MATERIAL IC
J 0
(3775 1780);
DISPLAY 0.510638 (3775 1780);
PAINT SKYBLUE (3775 1780);
FORCEPROP 1 LAST PART_NUMBER BEGR0278Z00
J 0
(3850 1775);
DISPLAY 0.510638 (3850 1775);
PAINT WHITE (3850 1775);
FORCEPROP 2 LAST COLOR LED_GREEN
J 0
(3975 1825);
DISPLAY 0.808511 (3975 1825);
PAINT GREEN (3975 1825);
FORCEPROP 2 LAST CDS_LIB pure_quanta
J 0
(3875 1700);
DISPLAY INVISIBLE (3875 1700);
FORCEPROP 1 LAST NEEDS_NO_SIZE TRUE
J 0
(3875 1700);
DISPLAY 0.468085 (3875 1700);
PAINT GREEN (3875 1700);
DISPLAY INVISIBLE (3875 1700);
FORCEPROP 0 LAST MANUF_PN 19-213/GVC-AMNB/3T
J 0
(3775 1975);
DISPLAY 0.808511 (3775 1975);
DISPLAY INVISIBLE (3775 1975);
FORCEPROP 1 LAST PATH I9
J 0
(4000 1780);
DISPLAY 0.723404 (4000 1780);
PAINT GREEN (4000 1780);
DISPLAY INVISIBLE (4000 1780);
FORCEPROP 1 LAST LOCATION D1
J 0
(3775 1885);
DISPLAY 0.702128 (3775 1885);
PAINT AQUA (3775 1885);
FORCEPROP 0 LASTPIN (3725 1700) $PN A
J 2
(3715 1710);
DISPLAY 0.680851 (3715 1710);
PAINT MONO (3715 1710);
FORCEPROP 0 LASTPIN (4025 1700) $PN C
J 0
(4035 1710);
DISPLAY 0.680851 (4035 1710);
PAINT MONO (4035 1710);
FORCEPROP 0 LAST $SEC 1
J 0
(3775 1925);
DISPLAY 0.680851 (3775 1925);
PAINT MONO (3775 1925);
DISPLAY INVISIBLE (3775 1925);
FORCEPROP 0 LAST CDS_SEC 1
J 0
(3775 1925);
DISPLAY 1.021277 (3775 1925);
DISPLAY INVISIBLE (3775 1925);
FORCEADD QUANTA_TITLE_BLOCK_C..1
(5925 -1775);
FORCEPROP 0 LAST CDS_CON_LAST_MODIFIED Fri Aug 25 17:25:47 2023
J 0
(4040 -1760);
DISPLAY INVISIBLE (4040 -1760);
FORCEPROP 2 LAST Q_DEPT 
J 1
(2162 -1726);
DISPLAY 1.957447 (2162 -1726);
PAINT GREEN (2162 -1726);
FORCEPROP 1 LAST CUSTOM_TXT_CDS <CON_LAST_MODIFIED>
J 0
(4040 -1760);
DISPLAY 0.978723 (4040 -1760);
FORCEPROP 2 LAST CUSTOM_TXT_CDS <XR_PAGE_TITLE>
J 0
(-1965 3475);
DISPLAY 0.638298 (-1965 3475);
PAINT PINK (-1965 3475);
DISPLAY INVISIBLE (-1965 3475);
FORCEPROP 1 LAST CUSTOM_TXT_CDS <NAME_2>
J 0
(2750 -1725);
FORCEPROP 1 LAST CUSTOM_TXT_CDS <NAME_1>
J 0
(2750 -1600);
FORCEPROP 1 LAST CUSTOM_TXT_CDS <Q_NUMBER>
J 0
(4522 -1672);
DISPLAY 1.212766 (4522 -1672);
FORCEPROP 1 LAST CUSTOM_TXT_CDS <Q_PROJ>
J 0
(3543 -1673);
DISPLAY 1.212766 (3543 -1673);
FORCEPROP 1 LAST CUSTOM_TXT_CDS <Q_REV>
J 0
(5741 -1672);
DISPLAY 1.212766 (5741 -1672);
FORCEPROP 1 LAST CUSTOM_TXT_CDS <CON_PAGE_NUM> OF <CON_TOTAL_PAGES>
J 0
(5479 -1757);
DISPLAY 0.978723 (5479 -1757);
FORCEPROP 1 LAST Q_TITLE LED PORT-80
J 0
(-3341 -1674);
DISPLAY 2.446809 (-3341 -1674);
PAINT GREEN (-3341 -1674);
FORCEPROP 1 LAST CDS_LMAN_SYM_OUTLINE -9475,6775,100,-125
J 0
(5925 -1775);
DISPLAY 0.468085 (5925 -1775);
PAINT GREEN (5925 -1775);
DISPLAY INVISIBLE (5925 -1775);
FORCEPROP 2 LAST CDS_LIB pure_quanta
J 0
(5925 -1775);
DISPLAY INVISIBLE (5925 -1775);
FORCEPROP 2 LAST PAGE_BORDER TRUE
J 0
(-1965 3475);
DISPLAY 0.638298 (-1965 3475);
PAINT PINK (-1965 3475);
DISPLAY INVISIBLE (-1965 3475);
FORCEPROP 1 LAST COMMENT_BODY TRUE
J 0
(5937 -1788);
DISPLAY 0.978723 (5937 -1788);
PAINT PEACH (5937 -1788);
DISPLAY INVISIBLE (5937 -1788);
FORCEPROP 2 LAST CDS_XR_PAGE_TITLE CR-47 : @SCM_LIB.SCM(SCH_1):PAGE47
J 0
(-1965 3475);
DISPLAY 0.638298 (-1965 3475);
PAINT PINK (-1965 3475);
DISPLAY INVISIBLE (-1965 3475);
WIRE 16 -1 (5075 1225)(5075 1400);
WIRE 16 -1 (4025 1400)(5075 1400);
WIRE 16 -1 (5075 1400)(5075 1700);
WIRE 16 -1 (4025 1700)(5075 1700);
WIRE 16 -1 (5075 1700)(5075 2000);
WIRE 16 -1 (4025 2000)(5075 2000);
WIRE 16 -1 (5075 2000)(5075 2300);
WIRE 16 -1 (4025 2300)(5075 2300);
WIRE 16 -1 (5075 2300)(5075 2600);
WIRE 16 -1 (4025 2600)(5075 2600);
WIRE 16 -1 (5075 2600)(5075 2900);
WIRE 16 -1 (4025 2900)(5075 2900);
WIRE 16 -1 (5075 2900)(5075 3200);
WIRE 16 -1 (4025 3200)(5075 3200);
WIRE 16 -1 (5075 3200)(5075 3500);
WIRE 16 -1 (4025 3500)(5075 3500);
WIRE 16 -1 (2775 1400)(3725 1400);
FORCEPROP 2 LAST SIG_NAME LED_POSTCODE_0_R
J 0
(2815 1410);
DISPLAY 0.808511 (2815 1410);
WIRE 16 -1 (2775 1700)(3725 1700);
FORCEPROP 2 LAST SIG_NAME LED_POSTCODE_1_R
J 0
(2815 1710);
DISPLAY 0.808511 (2815 1710);
WIRE 16 -1 (1500 1850)(425 1850);
FORCEPROP 2 LAST SIG_NAME LED_POSTCODE_1_R1
J 0
(440 1860);
DISPLAY 0.808511 (440 1860);
WIRE 16 -1 (1500 2750)(425 2750);
FORCEPROP 2 LAST SIG_NAME LED_POSTCODE_4_R1
J 0
(440 2760);
DISPLAY 0.808511 (440 2760);
WIRE 16 -1 (1500 2450)(425 2450);
FORCEPROP 2 LAST SIG_NAME LED_POSTCODE_3_R1
J 0
(440 2460);
DISPLAY 0.808511 (440 2460);
WIRE 16 -1 (1500 2150)(425 2150);
FORCEPROP 2 LAST SIG_NAME LED_POSTCODE_2_R1
J 0
(440 2160);
DISPLAY 0.808511 (440 2160);
WIRE 16 -1 (1500 1550)(425 1550);
FORCEPROP 2 LAST SIG_NAME LED_POSTCODE_0_R1
J 0
(440 1560);
DISPLAY 0.808511 (440 1560);
WIRE 16 -1 (1500 3650)(425 3650);
FORCEPROP 2 LAST SIG_NAME LED_POSTCODE_7_R1
J 0
(440 3660);
DISPLAY 0.808511 (440 3660);
WIRE 16 -1 (1500 3350)(425 3350);
FORCEPROP 2 LAST SIG_NAME LED_POSTCODE_6_R1
J 0
(440 3360);
DISPLAY 0.808511 (440 3360);
WIRE 16 -1 (1500 3050)(425 3050);
FORCEPROP 2 LAST SIG_NAME LED_POSTCODE_5_R1
J 0
(440 3060);
DISPLAY 0.808511 (440 3060);
WIRE 16 -1 (2775 3500)(3725 3500);
FORCEPROP 2 LAST SIG_NAME LED_POSTCODE_7_R
J 0
(2815 3510);
DISPLAY 0.808511 (2815 3510);
WIRE 16 -1 (2250 3650)(1700 3650);
WIRE 16 -1 (2250 3500)(2575 3500);
WIRE 16 -1 (1525 3500)(2250 3500);
FORCEPROP 2 LAST SIG_NAME LED_POSTCODE_7
J 0
(1615 3510);
DISPLAY 0.808511 (1615 3510);
WIRE 16 -1 (2250 3500)(2250 3650);
WIRE 16 -1 (2775 3200)(3725 3200);
FORCEPROP 2 LAST SIG_NAME LED_POSTCODE_6_R
J 0
(2815 3210);
DISPLAY 0.808511 (2815 3210);
WIRE 16 -1 (2250 3350)(1700 3350);
WIRE 16 -1 (2250 3200)(2575 3200);
WIRE 16 -1 (1525 3200)(2250 3200);
FORCEPROP 2 LAST SIG_NAME LED_POSTCODE_6
J 0
(1615 3210);
DISPLAY 0.808511 (1615 3210);
WIRE 16 -1 (2250 3200)(2250 3350);
WIRE 16 -1 (2775 2900)(3725 2900);
FORCEPROP 2 LAST SIG_NAME LED_POSTCODE_5_R
J 0
(2815 2910);
DISPLAY 0.808511 (2815 2910);
WIRE 16 -1 (2250 3050)(1700 3050);
WIRE 16 -1 (2250 2900)(2575 2900);
WIRE 16 -1 (1525 2900)(2250 2900);
FORCEPROP 2 LAST SIG_NAME LED_POSTCODE_5
J 0
(1615 2910);
DISPLAY 0.808511 (1615 2910);
WIRE 16 -1 (2250 2900)(2250 3050);
WIRE 16 -1 (2775 2600)(3725 2600);
FORCEPROP 2 LAST SIG_NAME LED_POSTCODE_4_R
J 0
(2815 2610);
DISPLAY 0.808511 (2815 2610);
WIRE 16 -1 (2250 2750)(1700 2750);
WIRE 16 -1 (2250 2600)(2575 2600);
WIRE 16 -1 (1525 2600)(2250 2600);
FORCEPROP 2 LAST SIG_NAME LED_POSTCODE_4
J 0
(1615 2610);
DISPLAY 0.808511 (1615 2610);
WIRE 16 -1 (2250 2600)(2250 2750);
WIRE 16 -1 (2775 2300)(3725 2300);
FORCEPROP 2 LAST SIG_NAME LED_POSTCODE_3_R
J 0
(2815 2310);
DISPLAY 0.808511 (2815 2310);
WIRE 16 -1 (2250 2450)(1700 2450);
WIRE 16 -1 (2250 2300)(2575 2300);
WIRE 16 -1 (1525 2300)(2250 2300);
FORCEPROP 2 LAST SIG_NAME LED_POSTCODE_3
J 0
(1615 2310);
DISPLAY 0.808511 (1615 2310);
WIRE 16 -1 (2250 2300)(2250 2450);
WIRE 16 -1 (2775 2000)(3725 2000);
FORCEPROP 2 LAST SIG_NAME LED_POSTCODE_2_R
J 0
(2815 2010);
DISPLAY 0.808511 (2815 2010);
WIRE 16 -1 (2250 2150)(1700 2150);
WIRE 16 -1 (2250 2000)(2575 2000);
WIRE 16 -1 (1525 2000)(2250 2000);
FORCEPROP 2 LAST SIG_NAME LED_POSTCODE_2
J 0
(1615 2010);
DISPLAY 0.808511 (1615 2010);
WIRE 16 -1 (2250 2000)(2250 2150);
WIRE 16 -1 (2250 1850)(1700 1850);
WIRE 16 -1 (2250 1700)(2575 1700);
WIRE 16 -1 (1525 1700)(2250 1700);
FORCEPROP 2 LAST SIG_NAME LED_POSTCODE_1
J 0
(1615 1710);
DISPLAY 0.808511 (1615 1710);
WIRE 16 -1 (2250 1700)(2250 1850);
WIRE 16 -1 (2250 1550)(1700 1550);
WIRE 16 -1 (2250 1400)(2575 1400);
WIRE 16 -1 (1525 1400)(2250 1400);
FORCEPROP 2 LAST SIG_NAME LED_POSTCODE_0
J 0
(1615 1410);
DISPLAY 0.808511 (1615 1410);
WIRE 16 -1 (2250 1400)(2250 1550);
DOT 1 (2250 3500);
DOT 1 (2250 1400);
DOT 1 (2250 1700);
DOT 1 (2250 2000);
DOT 1 (2250 2300);
DOT 1 (2250 2600);
DOT 1 (2250 2900);
DOT 1 (2250 3200);
DOT 1 (5075 1400);
DOT 1 (5075 1700);
DOT 1 (5075 2000);
DOT 1 (5075 2300);
DOT 1 (5075 2600);
DOT 1 (5075 2900);
DOT 1 (5075 3200);
FORCENOTE
LED GREEN VF=1.75V~2.35V
(2450 1100) 0;
DISPLAY LEFT (2450 1100);
DISPLAY 1.021277 (2450 1100);
FORCENOTE
IF RATING=25MA
(2450 900) 0;
DISPLAY LEFT (2450 900);
DISPLAY 1.021277 (2450 900);
FORCENOTE
IF=(3.3V-VF)/750 OHM=1.27MA~2.07MA
(2925 1000) 0;
DISPLAY LEFT (2925 1000);
DISPLAY 1.021277 (2925 1000);
FORCENOTE
IF=(3.3V-VF)/750 OHM=1.2MA~2.8MA
(2750 3875) 0;
DISPLAY LEFT (2750 3875);
DISPLAY 1.021277 (2750 3875);
FORCENOTE
SHOULD BE ARRANGE ACCORDING TO THE ORDER D0~D3 D4~D7
(125 4125) 0;
DISPLAY LEFT (125 4125);
DISPLAY 1.276596 (125 4125);
PAINT WHITE (125 4125);
FORCENOTE
LED RED VF=1.2V(TBD)~2.4V
(2350 3975) 0;
DISPLAY LEFT (2350 3975);
DISPLAY 1.021277 (2350 3975);
FORCENOTE
IF RATING=25MA
(2350 3775) 0;
DISPLAY LEFT (2350 3775);
DISPLAY 1.021277 (2350 3775);
FORCENOTE
PORT 80
(2525 400) 0;
DISPLAY LEFT (2525 400);
DISPLAY 4.914894 (2525 400);
PAINT WHITE (2525 400);
QUIT
